(kicad_pcb
	(version 20260206)
	(generator "pcbnew")
	(generator_version "10.0")
	(general
		(thickness 1.6)
		(legacy_teardrops no)
	)
	(paper "A4")
	(title_block
		(title "panther-plus-userver — 13130-1b_20150205.brd")
		(comment 1 "Honey Badger (Wiwynn) / footprint 894 of 1509 (DIMM1), pads 170-176 of 210")
	)
	(layers
		(0 "F.Cu" signal "TOP")
		(4 "In1.Cu" signal "L2")
		(6 "In2.Cu" signal "L3")
		(8 "In3.Cu" signal "L4")
		(10 "In4.Cu" signal "L5")
		(12 "In5.Cu" signal "L6")
		(14 "In6.Cu" signal "L7")
		(16 "In7.Cu" signal "L8")
		(18 "In8.Cu" signal "L9")
		(20 "In9.Cu" signal "L10")
		(22 "In10.Cu" signal "L11")
		(2 "B.Cu" signal "BOTTOM")
		(9 "F.Adhes" user "F.Adhesive")
		(11 "B.Adhes" user "B.Adhesive")
		(13 "F.Paste" user "Package Geometry/Pastemask Top")
		(15 "B.Paste" user "Package Geometry/Pastemask Bottom")
		(5 "F.SilkS" user "Ref Des/Silkscreen Top")
		(7 "B.SilkS" user "Ref Des/Silkscreen Bottom")
		(1 "F.Mask" user "Board Geometry/Soldermask Top")
		(3 "B.Mask" user "Board Geometry/Soldermask Bottom")
		(17 "Dwgs.User" user "User.Drawings")
		(19 "Cmts.User" user "User.Comments")
		(21 "Eco1.User" user "User.Eco1")
		(23 "Eco2.User" user "User.Eco2")
		(25 "Edge.Cuts" user "Board Geometry/Outline")
		(27 "Margin" user)
		(31 "F.CrtYd" user "Package Geometry/Place Bound Top")
		(29 "B.CrtYd" user "Package Geometry/Place Bound Bottom")
		(35 "F.Fab" user "Ref Des/Assembly Top")
		(33 "B.Fab" user "Ref Des/Assembly Bottom")
	)
	(footprint ""
		(layer "B.Cu")
		(at 158.500064 -66.699892 180)
		(property "Reference" "DIMM1"
			(at 0 0 0)
			(layer "B.SilkS")
			(hide yes)
			(effects
				(font
					(size 1.27 1.27)
				)
				(justify mirror)
			)
		)
		(property "Value" "DDR3-204P-142-COLAY-1-GP-U"
			(at 41.312338 -16.676878 180)
			(unlocked yes)
			(layer "B.Fab")
			(hide yes)
			(effects
				(font
					(size 1.016 1.016)
					(thickness 0.1524)
				)
				(justify mirror)
			)
		)
		(property "Device Type" "AS0A626-J8R6-7H-COLAY-1"
			(at 41.312338 -18.200878 180)
			(unlocked yes)
			(layer "B.Fab")
			(hide yes)
			(effects
				(font
					(size 1.016 1.016)
					(thickness 0.1524)
				)
				(justify mirror)
			)
		)
		(duplicate_pad_numbers_are_jumpers no)
		(pad "168" smd custom
			(at 20.850098 4.100068)
			(size 0.1143 0.1143)
			(layers "B.Cu" "B.Mask" "B.Paste")
			(net "M_A_DQ53")
			(options
				(clearance outline)
				(anchor circle)
			)
			(primitives
				(gr_poly
					(pts
						(xy 0 -0.9017) (xy -0.03175 -0.89916) (xy -0.0635 -0.889) (xy -0.09144 -0.87376) (xy -0.11684 -0.85344)
						(xy -0.13716 -0.82804) (xy -0.1524 -0.8001) (xy -0.16256 -0.76835) (xy -0.1651 -0.7366) (xy -0.1651 -0.11938)
						(xy -0.17272 -0.11176) (xy -0.19812 -0.0762) (xy -0.2032 -0.06604) (xy -0.20701 -0.05715) (xy -0.21209 -0.04699)
						(xy -0.2159 -0.03683) (xy -0.21844 -0.02667) (xy -0.22225 -0.01524) (xy -0.22352 -0.00508) (xy -0.22606 0.00508)
						(xy -0.22733 0.01651) (xy -0.22733 0.02667) (xy -0.2286 0.0381) (xy -0.22733 0.04953) (xy -0.22733 0.05969)
						(xy -0.22606 0.07112) (xy -0.22352 0.08128) (xy -0.22225 0.09144) (xy -0.21844 0.10287) (xy -0.2159 0.11303)
						(xy -0.21209 0.12319) (xy -0.20701 0.13335) (xy -0.2032 0.14224) (xy -0.19812 0.1524) (xy -0.17272 0.18796)
						(xy -0.1651 0.19558) (xy -0.1651 0.7366) (xy -0.16256 0.76835) (xy -0.1524 0.8001) (xy -0.13716 0.82804)
						(xy -0.11684 0.85344) (xy -0.09144 0.87376) (xy -0.0635 0.889) (xy -0.03175 0.89916) (xy 0 0.9017)
						(xy 0.03175 0.89916) (xy 0.0635 0.889) (xy 0.09144 0.87376) (xy 0.11684 0.85344) (xy 0.13716 0.82804)
						(xy 0.1524 0.8001) (xy 0.16256 0.76835) (xy 0.1651 0.7366) (xy 0.1651 0.19685) (xy 0.17272 0.18923)
						(xy 0.17907 0.18034) (xy 0.18669 0.17145) (xy 0.19177 0.16256) (xy 0.19812 0.15367) (xy 0.20828 0.13335)
						(xy 0.21971 0.10287) (xy 0.22225 0.09271) (xy 0.22479 0.08128) (xy 0.22606 0.07112) (xy 0.2286 0.05969)
						(xy 0.2286 0.01651) (xy 0.22606 0.00508) (xy 0.22479 -0.00508) (xy 0.22225 -0.01651) (xy 0.21971 -0.02667)
						(xy 0.20828 -0.05715) (xy 0.19812 -0.07747) (xy 0.19177 -0.08636) (xy 0.18669 -0.09525) (xy 0.17907 -0.10414)
						(xy 0.17272 -0.11303) (xy 0.1651 -0.12065) (xy 0.1651 -0.7366) (xy 0.16256 -0.76835) (xy 0.1524 -0.8001)
						(xy 0.13716 -0.82804) (xy 0.11684 -0.85344) (xy 0.09144 -0.87376) (xy 0.0635 -0.889) (xy 0.03175 -0.89916)
					)
					(width 0)
					(fill yes)
				)
			)
		)
		(pad "169" smd custom
			(at 21.150072 -4.100068)
			(size 0.1143 0.1143)
			(layers "B.Cu" "B.Mask" "B.Paste")
			(net "GND")
			(options
				(clearance outline)
				(anchor circle)
			)
			(primitives
				(gr_poly
					(pts
						(xy 0 -0.9017) (xy -0.03175 -0.89916) (xy -0.0635 -0.889) (xy -0.09144 -0.87376) (xy -0.11684 -0.85344)
						(xy -0.13716 -0.82804) (xy -0.1524 -0.8001) (xy -0.16256 -0.76835) (xy -0.1651 -0.7366) (xy -0.1651 -0.44958)
						(xy -0.17272 -0.44196) (xy -0.19812 -0.4064) (xy -0.2032 -0.39624) (xy -0.20701 -0.38735) (xy -0.21209 -0.37719)
						(xy -0.2159 -0.36703) (xy -0.21844 -0.35687) (xy -0.22225 -0.34544) (xy -0.22352 -0.33528) (xy -0.22606 -0.32512)
						(xy -0.22733 -0.31369) (xy -0.22733 -0.30353) (xy -0.2286 -0.2921) (xy -0.22733 -0.28067) (xy -0.22733 -0.27051)
						(xy -0.22606 -0.25908) (xy -0.22352 -0.24892) (xy -0.22225 -0.23876) (xy -0.21844 -0.22733) (xy -0.2159 -0.21717)
						(xy -0.21209 -0.20701) (xy -0.20701 -0.19685) (xy -0.2032 -0.18796) (xy -0.19812 -0.1778) (xy -0.17272 -0.14224)
						(xy -0.1651 -0.13462) (xy -0.1651 0.7366) (xy -0.16256 0.76835) (xy -0.1524 0.8001) (xy -0.13716 0.82804)
						(xy -0.11684 0.85344) (xy -0.09144 0.87376) (xy -0.0635 0.889) (xy -0.03175 0.89916) (xy 0 0.9017)
						(xy 0.03175 0.89916) (xy 0.0635 0.889) (xy 0.09144 0.87376) (xy 0.11684 0.85344) (xy 0.13716 0.82804)
						(xy 0.1524 0.8001) (xy 0.16256 0.76835) (xy 0.1651 0.7366) (xy 0.1651 -0.13462) (xy 0.17272 -0.14224)
						(xy 0.19812 -0.1778) (xy 0.2032 -0.18796) (xy 0.20701 -0.19685) (xy 0.21209 -0.20701) (xy 0.2159 -0.21717)
						(xy 0.21844 -0.22733) (xy 0.22225 -0.23876) (xy 0.22352 -0.24892) (xy 0.22606 -0.25908) (xy 0.22733 -0.27051)
						(xy 0.22733 -0.28067) (xy 0.2286 -0.2921) (xy 0.22733 -0.30353) (xy 0.22733 -0.31369) (xy 0.22606 -0.32512)
						(xy 0.22352 -0.33528) (xy 0.22225 -0.34544) (xy 0.21844 -0.35687) (xy 0.2159 -0.36703) (xy 0.21209 -0.37719)
						(xy 0.20701 -0.38735) (xy 0.2032 -0.39624) (xy 0.19812 -0.4064) (xy 0.17272 -0.44196) (xy 0.1651 -0.44958)
						(xy 0.1651 -0.7366) (xy 0.16256 -0.76835) (xy 0.1524 -0.8001) (xy 0.13716 -0.82804) (xy 0.11684 -0.85344)
						(xy 0.09144 -0.87376) (xy 0.0635 -0.889) (xy 0.03175 -0.89916)
					)
					(width 0)
					(fill yes)
				)
			)
		)
		(pad "170" smd custom
			(at 21.450046 4.100068)
			(size 0.1143 0.1143)
			(layers "B.Cu" "B.Mask" "B.Paste")
			(net "GND")
			(options
				(clearance outline)
				(anchor circle)
			)
			(primitives
				(gr_poly
					(pts
						(xy 0 -0.9017) (xy -0.03175 -0.89916) (xy -0.0635 -0.889) (xy -0.09144 -0.87376) (xy -0.11684 -0.85344)
						(xy -0.13716 -0.82804) (xy -0.1524 -0.8001) (xy -0.16256 -0.76835) (xy -0.1651 -0.7366) (xy -0.1651 0.13462)
						(xy -0.17272 0.14224) (xy -0.19812 0.1778) (xy -0.2032 0.18796) (xy -0.20701 0.19685) (xy -0.21209 0.20701)
						(xy -0.2159 0.21717) (xy -0.21844 0.22733) (xy -0.22225 0.23876) (xy -0.22352 0.24892) (xy -0.22606 0.25908)
						(xy -0.22733 0.27051) (xy -0.22733 0.28067) (xy -0.2286 0.2921) (xy -0.22733 0.30353) (xy -0.22733 0.31369)
						(xy -0.22606 0.32512) (xy -0.22352 0.33528) (xy -0.22225 0.34544) (xy -0.21844 0.35687) (xy -0.2159 0.36703)
						(xy -0.21209 0.37719) (xy -0.20701 0.38735) (xy -0.2032 0.39624) (xy -0.19812 0.4064) (xy -0.17272 0.44196)
						(xy -0.1651 0.44958) (xy -0.1651 0.7366) (xy -0.16256 0.76835) (xy -0.1524 0.8001) (xy -0.13716 0.82804)
						(xy -0.11684 0.85344) (xy -0.09144 0.87376) (xy -0.0635 0.889) (xy -0.03175 0.89916) (xy 0 0.9017)
						(xy 0.03175 0.89916) (xy 0.0635 0.889) (xy 0.09144 0.87376) (xy 0.11684 0.85344) (xy 0.13716 0.82804)
						(xy 0.1524 0.8001) (xy 0.16256 0.76835) (xy 0.1651 0.7366) (xy 0.1651 0.44958) (xy 0.17272 0.44196)
						(xy 0.19812 0.4064) (xy 0.2032 0.39624) (xy 0.20701 0.38735) (xy 0.21209 0.37719) (xy 0.2159 0.36703)
						(xy 0.21844 0.35687) (xy 0.22225 0.34544) (xy 0.22352 0.33528) (xy 0.22606 0.32512) (xy 0.22733 0.31369)
						(xy 0.22733 0.30353) (xy 0.2286 0.2921) (xy 0.22733 0.28067) (xy 0.22733 0.27051) (xy 0.22606 0.25908)
						(xy 0.22352 0.24892) (xy 0.22225 0.23876) (xy 0.21844 0.22733) (xy 0.2159 0.21717) (xy 0.21209 0.20701)
						(xy 0.20701 0.19685) (xy 0.2032 0.18796) (xy 0.19812 0.1778) (xy 0.17272 0.14224) (xy 0.1651 0.13462)
						(xy 0.1651 -0.7366) (xy 0.16256 -0.76835) (xy 0.1524 -0.8001) (xy 0.13716 -0.82804) (xy 0.11684 -0.85344)
						(xy 0.09144 -0.87376) (xy 0.0635 -0.889) (xy 0.03175 -0.89916)
					)
					(width 0)
					(fill yes)
				)
			)
		)
		(pad "171" smd custom
			(at 21.75002 -4.100068)
			(size 0.1143 0.1143)
			(layers "B.Cu" "B.Mask" "B.Paste")
			(net "M_A_DQS_DN6")
			(options
				(clearance outline)
				(anchor circle)
			)
			(primitives
				(gr_poly
					(pts
						(xy 0 -0.9017) (xy -0.03175 -0.89916) (xy -0.0635 -0.889) (xy -0.09144 -0.87376) (xy -0.11684 -0.85344)
						(xy -0.13716 -0.82804) (xy -0.1524 -0.8001) (xy -0.16256 -0.76835) (xy -0.1651 -0.7366) (xy -0.1651 -0.19685)
						(xy -0.17272 -0.18923) (xy -0.17907 -0.18034) (xy -0.18669 -0.17145) (xy -0.19177 -0.16256) (xy -0.19812 -0.15367)
						(xy -0.20828 -0.13335) (xy -0.21971 -0.10287) (xy -0.22225 -0.09271) (xy -0.22479 -0.08128) (xy -0.22606 -0.07112)
						(xy -0.2286 -0.05969) (xy -0.2286 -0.01651) (xy -0.22606 -0.00508) (xy -0.22479 0.00508) (xy -0.22225 0.01651)
						(xy -0.21971 0.02667) (xy -0.20828 0.05715) (xy -0.19812 0.07747) (xy -0.19177 0.08636) (xy -0.18669 0.09525)
						(xy -0.17907 0.10414) (xy -0.17272 0.11303) (xy -0.1651 0.12065) (xy -0.1651 0.7366) (xy -0.16256 0.76835)
						(xy -0.1524 0.8001) (xy -0.13716 0.82804) (xy -0.11684 0.85344) (xy -0.09144 0.87376) (xy -0.0635 0.889)
						(xy -0.03175 0.89916) (xy 0 0.9017) (xy 0.03175 0.89916) (xy 0.0635 0.889) (xy 0.09144 0.87376)
						(xy 0.11684 0.85344) (xy 0.13716 0.82804) (xy 0.1524 0.8001) (xy 0.16256 0.76835) (xy 0.1651 0.7366)
						(xy 0.1651 0.11938) (xy 0.17272 0.11176) (xy 0.19812 0.0762) (xy 0.2032 0.06604) (xy 0.20701 0.05715)
						(xy 0.21209 0.04699) (xy 0.2159 0.03683) (xy 0.21844 0.02667) (xy 0.22225 0.01524) (xy 0.22352 0.00508)
						(xy 0.22606 -0.00508) (xy 0.22733 -0.01651) (xy 0.22733 -0.02667) (xy 0.2286 -0.0381) (xy 0.22733 -0.04953)
						(xy 0.22733 -0.05969) (xy 0.22606 -0.07112) (xy 0.22352 -0.08128) (xy 0.22225 -0.09144) (xy 0.21844 -0.10287)
						(xy 0.2159 -0.11303) (xy 0.21209 -0.12319) (xy 0.20701 -0.13335) (xy 0.2032 -0.14224) (xy 0.19812 -0.1524)
						(xy 0.17272 -0.18796) (xy 0.1651 -0.19558) (xy 0.1651 -0.7366) (xy 0.16256 -0.76835) (xy 0.1524 -0.8001)
						(xy 0.13716 -0.82804) (xy 0.11684 -0.85344) (xy 0.09144 -0.87376) (xy 0.0635 -0.889) (xy 0.03175 -0.89916)
					)
					(width 0)
					(fill yes)
				)
			)
		)
		(pad "172" smd custom
			(at 22.049994 4.100068)
			(size 0.1143 0.1143)
			(layers "B.Cu" "B.Mask" "B.Paste")
			(net "GND")
			(options
				(clearance outline)
				(anchor circle)
			)
			(primitives
				(gr_poly
					(pts
						(xy 0 -0.9017) (xy -0.03175 -0.89916) (xy -0.0635 -0.889) (xy -0.09144 -0.87376) (xy -0.11684 -0.85344)
						(xy -0.13716 -0.82804) (xy -0.1524 -0.8001) (xy -0.16256 -0.76835) (xy -0.1651 -0.7366) (xy -0.1651 -0.11938)
						(xy -0.17272 -0.11176) (xy -0.19812 -0.0762) (xy -0.2032 -0.06604) (xy -0.20701 -0.05715) (xy -0.21209 -0.04699)
						(xy -0.2159 -0.03683) (xy -0.21844 -0.02667) (xy -0.22225 -0.01524) (xy -0.22352 -0.00508) (xy -0.22606 0.00508)
						(xy -0.22733 0.01651) (xy -0.22733 0.02667) (xy -0.2286 0.0381) (xy -0.22733 0.04953) (xy -0.22733 0.05969)
						(xy -0.22606 0.07112) (xy -0.22352 0.08128) (xy -0.22225 0.09144) (xy -0.21844 0.10287) (xy -0.2159 0.11303)
						(xy -0.21209 0.12319) (xy -0.20701 0.13335) (xy -0.2032 0.14224) (xy -0.19812 0.1524) (xy -0.17272 0.18796)
						(xy -0.1651 0.19558) (xy -0.1651 0.7366) (xy -0.16256 0.76835) (xy -0.1524 0.8001) (xy -0.13716 0.82804)
						(xy -0.11684 0.85344) (xy -0.09144 0.87376) (xy -0.0635 0.889) (xy -0.03175 0.89916) (xy 0 0.9017)
						(xy 0.03175 0.89916) (xy 0.0635 0.889) (xy 0.09144 0.87376) (xy 0.11684 0.85344) (xy 0.13716 0.82804)
						(xy 0.1524 0.8001) (xy 0.16256 0.76835) (xy 0.1651 0.7366) (xy 0.1651 0.19685) (xy 0.17272 0.18923)
						(xy 0.17907 0.18034) (xy 0.18669 0.17145) (xy 0.19177 0.16256) (xy 0.19812 0.15367) (xy 0.20828 0.13335)
						(xy 0.21971 0.10287) (xy 0.22225 0.09271) (xy 0.22479 0.08128) (xy 0.22606 0.07112) (xy 0.2286 0.05969)
						(xy 0.2286 0.01651) (xy 0.22606 0.00508) (xy 0.22479 -0.00508) (xy 0.22225 -0.01651) (xy 0.21971 -0.02667)
						(xy 0.20828 -0.05715) (xy 0.19812 -0.07747) (xy 0.19177 -0.08636) (xy 0.18669 -0.09525) (xy 0.17907 -0.10414)
						(xy 0.17272 -0.11303) (xy 0.1651 -0.12065) (xy 0.1651 -0.7366) (xy 0.16256 -0.76835) (xy 0.1524 -0.8001)
						(xy 0.13716 -0.82804) (xy 0.11684 -0.85344) (xy 0.09144 -0.87376) (xy 0.0635 -0.889) (xy 0.03175 -0.89916)
					)
					(width 0)
					(fill yes)
				)
			)
		)
		(pad "173" smd custom
			(at 22.349968 -4.100068)
			(size 0.1143 0.1143)
			(layers "B.Cu" "B.Mask" "B.Paste")
			(net "M_A_DQS_DP6")
			(options
				(clearance outline)
				(anchor circle)
			)
			(primitives
				(gr_poly
					(pts
						(xy 0 -0.9017) (xy -0.03175 -0.89916) (xy -0.0635 -0.889) (xy -0.09144 -0.87376) (xy -0.11684 -0.85344)
						(xy -0.13716 -0.82804) (xy -0.1524 -0.8001) (xy -0.16256 -0.76835) (xy -0.1651 -0.7366) (xy -0.1651 -0.44958)
						(xy -0.17272 -0.44196) (xy -0.19812 -0.4064) (xy -0.2032 -0.39624) (xy -0.20701 -0.38735) (xy -0.21209 -0.37719)
						(xy -0.2159 -0.36703) (xy -0.21844 -0.35687) (xy -0.22225 -0.34544) (xy -0.22352 -0.33528) (xy -0.22606 -0.32512)
						(xy -0.22733 -0.31369) (xy -0.22733 -0.30353) (xy -0.2286 -0.2921) (xy -0.22733 -0.28067) (xy -0.22733 -0.27051)
						(xy -0.22606 -0.25908) (xy -0.22352 -0.24892) (xy -0.22225 -0.23876) (xy -0.21844 -0.22733) (xy -0.2159 -0.21717)
						(xy -0.21209 -0.20701) (xy -0.20701 -0.19685) (xy -0.2032 -0.18796) (xy -0.19812 -0.1778) (xy -0.17272 -0.14224)
						(xy -0.1651 -0.13462) (xy -0.1651 0.7366) (xy -0.16256 0.76835) (xy -0.1524 0.8001) (xy -0.13716 0.82804)
						(xy -0.11684 0.85344) (xy -0.09144 0.87376) (xy -0.0635 0.889) (xy -0.03175 0.89916) (xy 0 0.9017)
						(xy 0.03175 0.89916) (xy 0.0635 0.889) (xy 0.09144 0.87376) (xy 0.11684 0.85344) (xy 0.13716 0.82804)
						(xy 0.1524 0.8001) (xy 0.16256 0.76835) (xy 0.1651 0.7366) (xy 0.1651 -0.13462) (xy 0.17272 -0.14224)
						(xy 0.19812 -0.1778) (xy 0.2032 -0.18796) (xy 0.20701 -0.19685) (xy 0.21209 -0.20701) (xy 0.2159 -0.21717)
						(xy 0.21844 -0.22733) (xy 0.22225 -0.23876) (xy 0.22352 -0.24892) (xy 0.22606 -0.25908) (xy 0.22733 -0.27051)
						(xy 0.22733 -0.28067) (xy 0.2286 -0.2921) (xy 0.22733 -0.30353) (xy 0.22733 -0.31369) (xy 0.22606 -0.32512)
						(xy 0.22352 -0.33528) (xy 0.22225 -0.34544) (xy 0.21844 -0.35687) (xy 0.2159 -0.36703) (xy 0.21209 -0.37719)
						(xy 0.20701 -0.38735) (xy 0.2032 -0.39624) (xy 0.19812 -0.4064) (xy 0.17272 -0.44196) (xy 0.1651 -0.44958)
						(xy 0.1651 -0.7366) (xy 0.16256 -0.76835) (xy 0.1524 -0.8001) (xy 0.13716 -0.82804) (xy 0.11684 -0.85344)
						(xy 0.09144 -0.87376) (xy 0.0635 -0.889) (xy 0.03175 -0.89916)
					)
					(width 0)
					(fill yes)
				)
			)
		)
		(pad "174" smd custom
			(at 22.649942 4.100068)
			(size 0.1143 0.1143)
			(layers "B.Cu" "B.Mask" "B.Paste")
			(net "M_A_DQ54")
			(options
				(clearance outline)
				(anchor circle)
			)
			(primitives
				(gr_poly
					(pts
						(xy 0 -0.9017) (xy -0.03175 -0.89916) (xy -0.0635 -0.889) (xy -0.09144 -0.87376) (xy -0.11684 -0.85344)
						(xy -0.13716 -0.82804) (xy -0.1524 -0.8001) (xy -0.16256 -0.76835) (xy -0.1651 -0.7366) (xy -0.1651 0.13462)
						(xy -0.17272 0.14224) (xy -0.19812 0.1778) (xy -0.2032 0.18796) (xy -0.20701 0.19685) (xy -0.21209 0.20701)
						(xy -0.2159 0.21717) (xy -0.21844 0.22733) (xy -0.22225 0.23876) (xy -0.22352 0.24892) (xy -0.22606 0.25908)
						(xy -0.22733 0.27051) (xy -0.22733 0.28067) (xy -0.2286 0.2921) (xy -0.22733 0.30353) (xy -0.22733 0.31369)
						(xy -0.22606 0.32512) (xy -0.22352 0.33528) (xy -0.22225 0.34544) (xy -0.21844 0.35687) (xy -0.2159 0.36703)
						(xy -0.21209 0.37719) (xy -0.20701 0.38735) (xy -0.2032 0.39624) (xy -0.19812 0.4064) (xy -0.17272 0.44196)
						(xy -0.1651 0.44958) (xy -0.1651 0.7366) (xy -0.16256 0.76835) (xy -0.1524 0.8001) (xy -0.13716 0.82804)
						(xy -0.11684 0.85344) (xy -0.09144 0.87376) (xy -0.0635 0.889) (xy -0.03175 0.89916) (xy 0 0.9017)
						(xy 0.03175 0.89916) (xy 0.0635 0.889) (xy 0.09144 0.87376) (xy 0.11684 0.85344) (xy 0.13716 0.82804)
						(xy 0.1524 0.8001) (xy 0.16256 0.76835) (xy 0.1651 0.7366) (xy 0.1651 0.44958) (xy 0.17272 0.44196)
						(xy 0.19812 0.4064) (xy 0.2032 0.39624) (xy 0.20701 0.38735) (xy 0.21209 0.37719) (xy 0.2159 0.36703)
						(xy 0.21844 0.35687) (xy 0.22225 0.34544) (xy 0.22352 0.33528) (xy 0.22606 0.32512) (xy 0.22733 0.31369)
						(xy 0.22733 0.30353) (xy 0.2286 0.2921) (xy 0.22733 0.28067) (xy 0.22733 0.27051) (xy 0.22606 0.25908)
						(xy 0.22352 0.24892) (xy 0.22225 0.23876) (xy 0.21844 0.22733) (xy 0.2159 0.21717) (xy 0.21209 0.20701)
						(xy 0.20701 0.19685) (xy 0.2032 0.18796) (xy 0.19812 0.1778) (xy 0.17272 0.14224) (xy 0.1651 0.13462)
						(xy 0.1651 -0.7366) (xy 0.16256 -0.76835) (xy 0.1524 -0.8001) (xy 0.13716 -0.82804) (xy 0.11684 -0.85344)
						(xy 0.09144 -0.87376) (xy 0.0635 -0.889) (xy 0.03175 -0.89916)
					)
					(width 0)
					(fill yes)
				)
			)
		)
	)
)
